(kicad_pcb
	(version 20260206)
	(generator "pcbnew")
	(generator_version "10.0")
	(general
		(thickness 1.6)
		(legacy_teardrops no)
	)
	(paper "A4")
	(title_block
		(title "Bryce Canyon_IOM_M2_16342-2_OCP.brd")
		(comment 1 "Bryce Canyon / footprints 521-528 of 1146")
	)
	(layers
		(0 "F.Cu" signal "TOP")
		(4 "In1.Cu" signal "L2GND")
		(6 "In2.Cu" signal "L3")
		(8 "In3.Cu" signal "L4VCC")
		(10 "In4.Cu" signal "L5VCC")
		(12 "In5.Cu" signal "L6")
		(14 "In6.Cu" signal "L7GND")
		(2 "B.Cu" signal "BOTTOM")
		(9 "F.Adhes" user "F.Adhesive")
		(11 "B.Adhes" user "B.Adhesive")
		(13 "F.Paste" user "Package Geometry/Pastemask Top")
		(15 "B.Paste" user "Package Geometry/Pastemask Bottom")
		(5 "F.SilkS" user "Ref Des/Silkscreen Top")
		(7 "B.SilkS" user "Ref Des/Silkscreen Bottom")
		(1 "F.Mask" user "Board Geometry/Soldermask Top")
		(3 "B.Mask" user "Board Geometry/Soldermask Bottom")
		(17 "Dwgs.User" user "User.Drawings")
		(19 "Cmts.User" user "User.Comments")
		(21 "Eco1.User" user "User.Eco1")
		(23 "Eco2.User" user "User.Eco2")
		(25 "Edge.Cuts" user "Board Geometry/Outline")
		(27 "Margin" user)
		(31 "F.CrtYd" user "Package Geometry/Place Bound Top")
		(29 "B.CrtYd" user "Package Geometry/Place Bound Bottom")
		(35 "F.Fab" user "Ref Des/Assembly Top")
		(33 "B.Fab" user "Ref Des/Assembly Bottom")
	)
	(footprint ""
		(layer "F.Cu")
		(at 94.1451 -48.720756 180)
		(property "Reference" "C507"
			(at 0 0 180)
			(layer "F.SilkS")
			(hide yes)
			(effects
				(font
					(size 1.27 1.27)
				)
			)
		)
		(property "Value" "SCD1U16V2KX-3GP"
			(at 1.1811 -2.7051 180)
			(unlocked yes)
			(layer "F.Fab")
			(hide yes)
			(effects
				(font
					(size 1.016 1.016)
					(thickness 0.1524)
				)
			)
		)
		(property "Device Type" "C402H22"
			(at 1.1811 -4.2291 180)
			(unlocked yes)
			(layer "F.Fab")
			(hide yes)
			(effects
				(font
					(size 1.016 1.016)
					(thickness 0.1524)
				)
			)
		)
		(duplicate_pad_numbers_are_jumpers no)
		(fp_rect
			(start -0.4318 0.9525)
			(end 0.4318 -0.9525)
			(stroke
				(width 0)
				(type default)
			)
			(fill no)
			(layer "F.CrtYd")
		)
		(fp_rect
			(start -0.4318 0.9525)
			(end 0.4318 -0.9525)
			(stroke
				(width 0)
				(type default)
			)
			(fill no)
			(layer "F.Fab")
		)
		(pad "1" smd custom
			(at 0 -0.4445 180)
			(size 0.1524 0.1524)
			(layers "F.Cu" "F.Mask" "F.Paste")
			(net "P3V3_EN_R")
			(options
				(clearance outline)
				(anchor circle)
			)
			(primitives
				(gr_poly
					(pts
						(arc
							(start 0.3048 -0.2032)
							(mid 0.275042 -0.275042)
							(end 0.2032 -0.3048)
						)
						(arc
							(start -0.2032 -0.3048)
							(mid -0.275042 -0.275042)
							(end -0.3048 -0.2032)
						)
						(arc
							(start -0.3048 0.2032)
							(mid -0.275042 0.275042)
							(end -0.2032 0.3048)
						)
						(arc
							(start 0.2032 0.3048)
							(mid 0.275042 0.275042)
							(end 0.3048 0.2032)
						)
					)
					(width 0)
					(fill yes)
				)
			)
		)
		(pad "2" smd custom
			(at 0 0.4445 180)
			(size 0.1524 0.1524)
			(layers "F.Cu" "F.Mask" "F.Paste")
			(net "GND")
			(options
				(clearance outline)
				(anchor circle)
			)
			(primitives
				(gr_poly
					(pts
						(arc
							(start 0.3048 -0.2032)
							(mid 0.275042 -0.275042)
							(end 0.2032 -0.3048)
						)
						(arc
							(start -0.2032 -0.3048)
							(mid -0.275042 -0.275042)
							(end -0.3048 -0.2032)
						)
						(arc
							(start -0.3048 0.2032)
							(mid -0.275042 0.275042)
							(end -0.2032 0.3048)
						)
						(arc
							(start 0.2032 0.3048)
							(mid 0.275042 0.275042)
							(end 0.3048 0.2032)
						)
					)
					(width 0)
					(fill yes)
				)
			)
		)
	)
	(footprint ""
		(layer "F.Cu")
		(at 94.03588 -148.230844)
		(property "Reference" "C18"
			(at 0 0 0)
			(layer "F.SilkS")
			(hide yes)
			(effects
				(font
					(size 1.27 1.27)
				)
			)
		)
		(property "Value" "SC1U16V3KX-5GP"
			(at 0 -2.8194 0)
			(unlocked yes)
			(layer "F.Fab")
			(hide yes)
			(effects
				(font
					(size 1.016 1.016)
					(thickness 0.1524)
				)
			)
		)
		(property "Device Type" "C603H36"
			(at 0 -4.3434 0)
			(unlocked yes)
			(layer "F.Fab")
			(hide yes)
			(effects
				(font
					(size 1.016 1.016)
					(thickness 0.1524)
				)
			)
		)
		(duplicate_pad_numbers_are_jumpers no)
		(fp_line
			(start 0.508 0)
			(end -0.508 0)
			(stroke
				(width 0.2032)
				(type default)
			)
			(layer "F.SilkS")
		)
		(fp_rect
			(start -0.5842 1.3335)
			(end 0.5842 -1.3335)
			(stroke
				(width 0)
				(type default)
			)
			(fill no)
			(layer "F.CrtYd")
		)
		(fp_rect
			(start -0.5842 1.3335)
			(end 0.5842 -1.3335)
			(stroke
				(width 0)
				(type default)
			)
			(fill no)
			(layer "F.Fab")
		)
		(pad "1" smd custom
			(at 0 -0.762)
			(size 0.2159 0.2159)
			(layers "F.Cu" "F.Mask" "F.Paste")
			(net "CRFILT")
			(options
				(clearance outline)
				(anchor circle)
			)
			(primitives
				(gr_poly
					(pts
						(arc
							(start -0.3302 -0.4318)
							(mid -0.402042 -0.402042)
							(end -0.4318 -0.3302)
						)
						(arc
							(start -0.4318 0.3302)
							(mid -0.402042 0.402042)
							(end -0.3302 0.4318)
						)
						(arc
							(start 0.3302 0.4318)
							(mid 0.402042 0.402042)
							(end 0.4318 0.3302)
						)
						(arc
							(start 0.4318 -0.3302)
							(mid 0.402042 -0.402042)
							(end 0.3302 -0.4318)
						)
					)
					(width 0)
					(fill yes)
				)
			)
		)
		(pad "2" smd custom
			(at 0 0.762)
			(size 0.2159 0.2159)
			(layers "F.Cu" "F.Mask" "F.Paste")
			(net "GND")
			(options
				(clearance outline)
				(anchor circle)
			)
			(primitives
				(gr_poly
					(pts
						(arc
							(start -0.3302 -0.4318)
							(mid -0.402042 -0.402042)
							(end -0.4318 -0.3302)
						)
						(arc
							(start -0.4318 0.3302)
							(mid -0.402042 0.402042)
							(end -0.3302 0.4318)
						)
						(arc
							(start 0.3302 0.4318)
							(mid 0.402042 0.402042)
							(end 0.4318 0.3302)
						)
						(arc
							(start 0.4318 -0.3302)
							(mid 0.402042 -0.402042)
							(end 0.3302 -0.4318)
						)
					)
					(width 0)
					(fill yes)
				)
			)
		)
	)
	(footprint ""
		(layer "F.Cu")
		(at 52.832 -132.207)
		(property "Reference" "TP10"
			(at 0 0 0)
			(layer "F.SilkS")
			(hide yes)
			(effects
				(font
					(size 1.27 1.27)
				)
			)
		)
		(property "Value" "TPAD28-2-GP"
			(at -0.0127 -1.6637 0)
			(unlocked yes)
			(layer "F.Fab")
			(hide yes)
			(effects
				(font
					(size 1.016 1.016)
					(thickness 0.1524)
				)
			)
		)
		(property "Device Type" "TPAD28"
			(at -0.0127 -3.1877 0)
			(unlocked yes)
			(layer "F.Fab")
			(hide yes)
			(effects
				(font
					(size 1.016 1.016)
					(thickness 0.1524)
				)
			)
		)
		(duplicate_pad_numbers_are_jumpers no)
		(fp_poly
			(pts
				(arc
					(start 0.3556 0)
					(mid -0.3556 0)
					(end 0.3556 0)
				)
			)
			(stroke
				(width 0)
				(type default)
			)
			(fill no)
			(layer "F.CrtYd")
		)
		(fp_poly
			(pts
				(arc
					(start 0.6096 0)
					(mid -0.6096 0)
					(end 0.6096 0)
				)
			)
			(stroke
				(width 0)
				(type default)
			)
			(fill no)
			(layer "F.Fab")
		)
		(pad "1" smd circle
			(at 0 0)
			(size 0.7112 0.7112)
			(layers "F.Cu" "F.Mask" "F.Paste")
			(net "TP_BMC0_LPC_LAD1")
		)
	)
	(footprint ""
		(layer "F.Cu")
		(at 57.216548 -131.28752 180)
		(property "Reference" "R288"
			(at 0 0 180)
			(layer "F.SilkS")
			(hide yes)
			(effects
				(font
					(size 1.27 1.27)
				)
			)
		)
		(property "Value" "0R2J-2-GP"
			(at 0.064008 -3.993896 180)
			(unlocked yes)
			(layer "F.Fab")
			(hide yes)
			(effects
				(font
					(size 1.016 1.016)
					(thickness 0.1524)
				)
			)
		)
		(property "Device Type" "R402H16"
			(at 0.064008 -5.517896 180)
			(unlocked yes)
			(layer "F.Fab")
			(hide yes)
			(effects
				(font
					(size 1.016 1.016)
					(thickness 0.1524)
				)
			)
		)
		(duplicate_pad_numbers_are_jumpers no)
		(fp_line
			(start 0.508 -0.9398)
			(end -0.508 -0.9398)
			(stroke
				(width 0.1524)
				(type default)
			)
			(layer "F.SilkS")
		)
		(fp_line
			(start -0.508 -0.9398)
			(end -0.508 0.9398)
			(stroke
				(width 0.1524)
				(type default)
			)
			(layer "F.SilkS")
		)
		(fp_rect
			(start -0.508 0.9398)
			(end 0.508 -0.9398)
			(stroke
				(width 0)
				(type default)
			)
			(fill no)
			(layer "F.CrtYd")
		)
		(fp_rect
			(start -0.508 0.9398)
			(end 0.508 -0.9398)
			(stroke
				(width 0)
				(type default)
			)
			(fill no)
			(layer "F.Fab")
		)
		(pad "1" smd custom
			(at 0 -0.4445 180)
			(size 0.1397 0.1397)
			(layers "F.Cu" "F.Mask" "F.Paste")
			(net "EXP_SPARE_0")
			(options
				(clearance outline)
				(anchor circle)
			)
			(primitives
				(gr_poly
					(pts
						(arc
							(start -0.1778 -0.2794)
							(mid -0.249642 -0.249642)
							(end -0.2794 -0.1778)
						)
						(arc
							(start -0.2794 0.1778)
							(mid -0.249642 0.249642)
							(end -0.1778 0.2794)
						)
						(arc
							(start 0.1778 0.2794)
							(mid 0.249642 0.249642)
							(end 0.2794 0.1778)
						)
						(arc
							(start 0.2794 -0.1778)
							(mid 0.249642 -0.249642)
							(end 0.1778 -0.2794)
						)
					)
					(width 0)
					(fill yes)
				)
			)
		)
		(pad "2" smd custom
			(at 0 0.4445 180)
			(size 0.1397 0.1397)
			(layers "F.Cu" "F.Mask" "F.Paste")
			(net "EXP_SPARE_0_R")
			(options
				(clearance outline)
				(anchor circle)
			)
			(primitives
				(gr_poly
					(pts
						(arc
							(start -0.1778 -0.2794)
							(mid -0.249642 -0.249642)
							(end -0.2794 -0.1778)
						)
						(arc
							(start -0.2794 0.1778)
							(mid -0.249642 0.249642)
							(end -0.1778 0.2794)
						)
						(arc
							(start 0.1778 0.2794)
							(mid 0.249642 0.249642)
							(end 0.2794 0.1778)
						)
						(arc
							(start 0.2794 -0.1778)
							(mid 0.249642 -0.249642)
							(end 0.1778 -0.2794)
						)
					)
					(width 0)
					(fill yes)
				)
			)
		)
	)
	(footprint ""
		(layer "F.Cu")
		(at 71.7804 -173.7106 180)
		(property "Reference" "C78"
			(at 0 0 180)
			(layer "F.SilkS")
			(hide yes)
			(effects
				(font
					(size 1.27 1.27)
				)
			)
		)
		(property "Value" "SCD1U16V2KX-3GP"
			(at 1.1811 -2.7051 180)
			(unlocked yes)
			(layer "F.Fab")
			(hide yes)
			(effects
				(font
					(size 1.016 1.016)
					(thickness 0.1524)
				)
			)
		)
		(property "Device Type" "C402H22"
			(at 1.1811 -4.2291 180)
			(unlocked yes)
			(layer "F.Fab")
			(hide yes)
			(effects
				(font
					(size 1.016 1.016)
					(thickness 0.1524)
				)
			)
		)
		(duplicate_pad_numbers_are_jumpers no)
		(fp_rect
			(start -0.4318 0.9525)
			(end 0.4318 -0.9525)
			(stroke
				(width 0)
				(type default)
			)
			(fill no)
			(layer "F.CrtYd")
		)
		(fp_rect
			(start -0.4318 0.9525)
			(end 0.4318 -0.9525)
			(stroke
				(width 0)
				(type default)
			)
			(fill no)
			(layer "F.Fab")
		)
		(pad "1" smd custom
			(at 0 -0.4445 180)
			(size 0.1524 0.1524)
			(layers "F.Cu" "F.Mask" "F.Paste")
			(net "P3V3_STBY")
			(options
				(clearance outline)
				(anchor circle)
			)
			(primitives
				(gr_poly
					(pts
						(arc
							(start 0.3048 -0.2032)
							(mid 0.275042 -0.275042)
							(end 0.2032 -0.3048)
						)
						(arc
							(start -0.2032 -0.3048)
							(mid -0.275042 -0.275042)
							(end -0.3048 -0.2032)
						)
						(arc
							(start -0.3048 0.2032)
							(mid -0.275042 0.275042)
							(end -0.2032 0.3048)
						)
						(arc
							(start 0.2032 0.3048)
							(mid 0.275042 0.275042)
							(end 0.3048 0.2032)
						)
					)
					(width 0)
					(fill yes)
				)
			)
		)
		(pad "2" smd custom
			(at 0 0.4445 180)
			(size 0.1524 0.1524)
			(layers "F.Cu" "F.Mask" "F.Paste")
			(net "GND")
			(options
				(clearance outline)
				(anchor circle)
			)
			(primitives
				(gr_poly
					(pts
						(arc
							(start 0.3048 -0.2032)
							(mid 0.275042 -0.275042)
							(end 0.2032 -0.3048)
						)
						(arc
							(start -0.2032 -0.3048)
							(mid -0.275042 -0.275042)
							(end -0.3048 -0.2032)
						)
						(arc
							(start -0.3048 0.2032)
							(mid -0.275042 0.275042)
							(end -0.2032 0.3048)
						)
						(arc
							(start 0.2032 0.3048)
							(mid 0.275042 0.275042)
							(end 0.3048 0.2032)
						)
					)
					(width 0)
					(fill yes)
				)
			)
		)
	)
	(footprint ""
		(layer "F.Cu")
		(at 226.217988 -18.469356)
		(property "Reference" "C165"
			(at 0 0 0)
			(layer "F.SilkS")
			(hide yes)
			(effects
				(font
					(size 1.27 1.27)
				)
			)
		)
		(property "Value" "SC10U16V5KX-7-GP-U"
			(at -0.0762 -6.1214 0)
			(unlocked yes)
			(layer "F.Fab")
			(hide yes)
			(effects
				(font
					(size 1.016 1.016)
					(thickness 0.1524)
				)
			)
		)
		(property "Device Type" "C805H58"
			(at -0.0762 -8.1534 0)
			(unlocked yes)
			(layer "F.Fab")
			(hide yes)
			(effects
				(font
					(size 1.016 1.016)
					(thickness 0.1524)
				)
			)
		)
		(duplicate_pad_numbers_are_jumpers no)
		(fp_line
			(start 0.635 0)
			(end -0.635 0)
			(stroke
				(width 0.508)
				(type default)
			)
			(layer "F.SilkS")
		)
		(fp_rect
			(start -0.9652 1.778)
			(end 0.9652 -1.778)
			(stroke
				(width 0)
				(type default)
			)
			(fill no)
			(layer "F.CrtYd")
		)
		(fp_poly
			(pts
				(xy -0.9652 -1.778) (xy 0.9652 -1.778) (xy 0.9652 1.778) (xy -0.9652 1.778)
			)
			(stroke
				(width 0)
				(type default)
			)
			(fill no)
			(layer "F.Fab")
		)
		(pad "1" smd rect
			(at 0 -0.9652)
			(size 1.397 1.143)
			(layers "F.Cu" "F.Mask" "F.Paste")
			(net "P5V_STBY")
		)
		(pad "2" smd rect
			(at 0 0.9652)
			(size 1.397 1.143)
			(layers "F.Cu" "F.Mask" "F.Paste")
			(net "GND")
		)
	)
	(footprint ""
		(layer "F.Cu")
		(at 62.770512 -136.31164 -90)
		(property "Reference" "R352"
			(at 0 0 270)
			(layer "F.SilkS")
			(hide yes)
			(effects
				(font
					(size 1.27 1.27)
				)
			)
		)
		(property "Value" "4K7R2F-GP"
			(at 0.064008 -3.993896 270)
			(unlocked yes)
			(layer "F.Fab")
			(hide yes)
			(effects
				(font
					(size 1.016 1.016)
					(thickness 0.1524)
				)
			)
		)
		(property "Device Type" "R402H16"
			(at 0.064008 -5.517896 270)
			(unlocked yes)
			(layer "F.Fab")
			(hide yes)
			(effects
				(font
					(size 1.016 1.016)
					(thickness 0.1524)
				)
			)
		)
		(duplicate_pad_numbers_are_jumpers no)
		(fp_line
			(start -0.508 -0.9398)
			(end -0.508 0.9398)
			(stroke
				(width 0.1524)
				(type default)
			)
			(layer "F.SilkS")
		)
		(fp_line
			(start 0.508 -0.9398)
			(end -0.508 -0.9398)
			(stroke
				(width 0.1524)
				(type default)
			)
			(layer "F.SilkS")
		)
		(fp_rect
			(start -0.508 0.9398)
			(end 0.508 -0.9398)
			(stroke
				(width 0)
				(type default)
			)
			(fill no)
			(layer "F.CrtYd")
		)
		(fp_rect
			(start -0.508 0.9398)
			(end 0.508 -0.9398)
			(stroke
				(width 0)
				(type default)
			)
			(fill no)
			(layer "F.Fab")
		)
		(pad "1" smd custom
			(at 0 -0.4445 270)
			(size 0.1397 0.1397)
			(layers "F.Cu" "F.Mask" "F.Paste")
			(net "P3V3_STBY")
			(options
				(clearance outline)
				(anchor circle)
			)
			(primitives
				(gr_poly
					(pts
						(arc
							(start -0.1778 -0.2794)
							(mid -0.249642 -0.249642)
							(end -0.2794 -0.1778)
						)
						(arc
							(start -0.2794 0.1778)
							(mid -0.249642 0.249642)
							(end -0.1778 0.2794)
						)
						(arc
							(start 0.1778 0.2794)
							(mid 0.249642 0.249642)
							(end 0.2794 0.1778)
						)
						(arc
							(start 0.2794 -0.1778)
							(mid 0.249642 -0.249642)
							(end 0.1778 -0.2794)
						)
					)
					(width 0)
					(fill yes)
				)
			)
		)
		(pad "2" smd custom
			(at 0 0.4445 270)
			(size 0.1397 0.1397)
			(layers "F.Cu" "F.Mask" "F.Paste")
			(net "SLOTID_0")
			(options
				(clearance outline)
				(anchor circle)
			)
			(primitives
				(gr_poly
					(pts
						(arc
							(start -0.1778 -0.2794)
							(mid -0.249642 -0.249642)
							(end -0.2794 -0.1778)
						)
						(arc
							(start -0.2794 0.1778)
							(mid -0.249642 0.249642)
							(end -0.1778 0.2794)
						)
						(arc
							(start 0.1778 0.2794)
							(mid 0.249642 0.249642)
							(end 0.2794 0.1778)
						)
						(arc
							(start 0.2794 -0.1778)
							(mid 0.249642 -0.249642)
							(end 0.1778 -0.2794)
						)
					)
					(width 0)
					(fill yes)
				)
			)
		)
	)
	(footprint ""
		(layer "F.Cu")
		(at 153.351738 -16.486378 180)
		(property "Reference" "C202"
			(at 0 0 180)
			(layer "F.SilkS")
			(hide yes)
			(effects
				(font
					(size 1.27 1.27)
				)
			)
		)
		(property "Value" "SC1U16V3KX-5GP"
			(at 0 -2.8194 180)
			(unlocked yes)
			(layer "F.Fab")
			(hide yes)
			(effects
				(font
					(size 1.016 1.016)
					(thickness 0.1524)
				)
			)
		)
		(property "Device Type" "C603H36"
			(at 0 -4.3434 180)
			(unlocked yes)
			(layer "F.Fab")
			(hide yes)
			(effects
				(font
					(size 1.016 1.016)
					(thickness 0.1524)
				)
			)
		)
		(duplicate_pad_numbers_are_jumpers no)
		(fp_line
			(start 0.508 0)
			(end -0.508 0)
			(stroke
				(width 0.2032)
				(type default)
			)
			(layer "F.SilkS")
		)
		(fp_rect
			(start -0.5842 1.3335)
			(end 0.5842 -1.3335)
			(stroke
				(width 0)
				(type default)
			)
			(fill no)
			(layer "F.CrtYd")
		)
		(fp_rect
			(start -0.5842 1.3335)
			(end 0.5842 -1.3335)
			(stroke
				(width 0)
				(type default)
			)
			(fill no)
			(layer "F.Fab")
		)
		(pad "1" smd custom
			(at 0 -0.762 180)
			(size 0.2159 0.2159)
			(layers "F.Cu" "F.Mask" "F.Paste")
			(net "P12V_STBY_VCC_PU4")
			(options
				(clearance outline)
				(anchor circle)
			)
			(primitives
				(gr_poly
					(pts
						(arc
							(start -0.3302 -0.4318)
							(mid -0.402042 -0.402042)
							(end -0.4318 -0.3302)
						)
						(arc
							(start -0.4318 0.3302)
							(mid -0.402042 0.402042)
							(end -0.3302 0.4318)
						)
						(arc
							(start 0.3302 0.4318)
							(mid 0.402042 0.402042)
							(end 0.4318 0.3302)
						)
						(arc
							(start 0.4318 -0.3302)
							(mid 0.402042 -0.402042)
							(end 0.3302 -0.4318)
						)
					)
					(width 0)
					(fill yes)
				)
			)
		)
		(pad "2" smd custom
			(at 0 0.762 180)
			(size 0.2159 0.2159)
			(layers "F.Cu" "F.Mask" "F.Paste")
			(net "GND")
			(options
				(clearance outline)
				(anchor circle)
			)
			(primitives
				(gr_poly
					(pts
						(arc
							(start -0.3302 -0.4318)
							(mid -0.402042 -0.402042)
							(end -0.4318 -0.3302)
						)
						(arc
							(start -0.4318 0.3302)
							(mid -0.402042 0.402042)
							(end -0.3302 0.4318)
						)
						(arc
							(start 0.3302 0.4318)
							(mid 0.402042 0.402042)
							(end 0.4318 0.3302)
						)
						(arc
							(start 0.4318 -0.3302)
							(mid 0.402042 -0.402042)
							(end 0.3302 -0.4318)
						)
					)
					(width 0)
					(fill yes)
				)
			)
		)
	)
)
